# Bryce Canyon_Front_Drive_Plane_Board_Stackup.xlsx — Stack up_16315-1 (pcb-stackup)
|  |  |  |  |  | Version |  |  |  |  |  |  |  |  |  |  |  |  |  |  |  |  |  |  |  |
| Board Number: |  | 16315-1 |  |  | 02 |  |  |  |  |  |  |  |  |  |  |  |  |  |  |  |  |  |  |  |
| Project name: |  | Bryce Canyon |  |  |  |  |  |  |  |  |  |  |  |  |  |  |  |  |  |  |  |  |  |  |
| Model Name: |  | Front Drive Plane Board |  |  |  |  |  |  |  |  |  |  |  |  |  |  |  |  |  |  |  |  |  |  |
| Layer Count: |  | 12 Layer |  |  |  |  |  |  |  |  |  |  |  |  |  |  |  |  |  |  |  |  |  |  |
| Date: |  | 2017-09-25 00:00:00 |  |  |  |  |  |  |  |  |  |  |  |  |  |  |  |  |  |  |  |  |  |  |
| Low Loss Material: |  | TU863+VLP (Tg : 180/Td : 370) |  |  |  |  |  | Single Ended Type(mil) |  |  |  |  | Differential Type(mil) |  |  |  |  |  |  |  |  |  |  |  |
| Gold Finger(Y/N): |  | N |  |  |  |  | Imp | 50 |  |  |  | Imp | 85 |  |  |  |  |  | 100 |  |  |  |  |  |
| Customer: |  | <name> |  |  |  |  | Variation | Inner/Outer+/-5ohm |  |  |  | Variation | Inner/Outer+/-10% |  |  |  |  |  | Inner/Outer+/-10% |  |  |  |  |  |
| EE engineer |  | <name> |  |  |  |  | Bus | MISC. |  |  |  | Bus | PCIe / Clock |  |  |  |  |  | SATA |  |  |  |  |  |
| SI Engineer |  | <name> |  |  |  |  |  |  |  |  |  |  |  |  |  |  |  |  |  |  |  |  |  |  |
|  |  |  |  |  |  |  | Type | SE |  |  |  | Type | DP |  |  |  |  |  | DP |  |  |  |  |  |
| Layer |  |  | Thickness | Glass/Copper Style | Er | Df(1G) | Layers | 1,3,5,8,10,12 |  |  |  | Layers | 1,3,5,8,10,12 |  |  |  |  |  | 1,3,5,8,10,12 |  |  |  |  |  |
|  |  | Cu oz | Wiwynn |  | Wiwynn |  |  | Wiwynn |  |  |  |  | Wiwynn |  |  |  |  |  | Wiwynn |  |  |  |  |  |
|  | Mask |  | 0.5 |  | 3.4 | 0.025 |  | Width | Imp | Width | Imp |  | Width | Space | Imp | Width | Space | Imp | Width | Space | Imp | Width | Space | Imp |
| Top | Signal | 0.5 oz+plating | 2.1 |  |  |  | S1 | 6.75(L2) | 50.17 |  |  | S1 | 6.5(L2) | 5 | 84.97 |  |  |  | 5(L2) | 6.5 | 99.87 |  |  |  |
|  | Prepreg |  | 4 |  | 3.8 | 0.006 |  |  |  |  |  |  |  |  |  |  |  |  |  |  |  |  |  |  |
| L2 | GND | 1 oz | 1.3 |  |  |  | P2 | reference layer |  |  |  | P2 | reference layer |  |  |  |  |  | reference layer |  |  |  |  |  |
|  | Core |  | 5 |  | 3.8 | 0.006 |  |  |  |  |  |  |  |  |  |  |  |  |  |  |  |  |  |  |
| L3 | Signal | 1 oz | 1.3 |  |  |  | S3 | 5.25(L2/L4) | 49.65 |  |  | S3 | 5.5(L2/L4) | 6 | 85.19 |  |  |  | 4.25(L2/L4) | 8.75 | 99.77 |  |  |  |
|  | Prepreg |  | 9 |  | 4.2 | 0.006 |  |  |  |  |  |  |  |  |  |  |  |  |  |  |  |  |  |  |
| L4 | GND | 1 oz | 1.3 |  |  |  | P4 | reference layer |  |  |  | P4 | reference layer |  |  |  |  |  | reference layer |  |  |  |  |  |
|  | Core |  | 4 |  | 3.8 | 0.006 |  |  |  |  |  |  |  |  |  |  |  |  |  |  |  |  |  |  |
| L5 | Signal | 1 oz | 1.3 |  |  |  | S5 | 4.75(L4/L6) | 49.49 |  |  | S5 | 5(L4/L6) | 6 | 84.86 |  |  |  | 4(L4/L6) | 9 | 99.07 |  |  |  |
|  | Prepreg |  | 12 |  | 4.2 | 0.006 |  |  |  |  |  |  |  |  |  |  |  |  |  |  |  |  |  |  |
| L6 | POWER | 2 oz | 2.6 |  |  |  | P6 | reference layer |  |  |  | P6 | reference layer |  |  |  |  |  | reference layer |  |  |  |  |  |
|  | Core |  | 4 |  | 4 | 0.006 |  |  |  |  |  |  |  |  |  |  |  |  |  |  |  |  |  |  |
| L7 | POWER | 2 oz | 2.6 |  |  |  | P7 | reference layer |  |  |  | P7 | reference layer |  |  |  |  |  | reference layer |  |  |  |  |  |
|  | Prepreg |  | 12 |  | 4.2 | 0.006 |  |  |  |  |  |  |  |  |  |  |  |  |  |  |  |  |  |  |
| L8 | Signal | 1 oz | 1.3 |  |  |  | S8 | 4.75(L7/L9) | 49.49 |  |  | S8 | 5(L7/L9) | 6 | 84.86 |  |  |  | 4(L7/L9) | 9 | 99.07 |  |  |  |
|  | Core |  | 4 |  | 3.8 | 0.006 |  |  |  |  |  |  |  |  |  |  |  |  |  |  |  |  |  |  |
| L9 | GND | 1 oz | 1.3 |  |  |  | P9 | reference layer |  |  |  | P9 | reference layer |  |  |  |  |  | reference layer |  |  |  |  |  |
|  | Prepreg |  | 9 |  | 4.2 | 0.006 |  |  |  |  |  |  |  |  |  |  |  |  |  |  |  |  |  |  |
| L10 | Signal | 1 oz | 1.3 |  |  |  | S10 | 5.25(L9/L11) | 49.65 |  |  | S10 | 5.5(L9/L11) | 6 | 85.19 |  |  |  | 4.25(L9/L11) | 8.75 | 99.77 |  |  |  |
|  | Core |  | 5 |  | 3.8 | 0.006 |  |  |  |  |  |  |  |  |  |  |  |  |  |  |  |  |  |  |
| L11 | GND | 1 oz | 1.3 |  |  |  | P11 | reference layer |  |  |  | P11 | reference layer |  |  |  |  |  | reference layer |  |  |  |  |  |
|  | Prepreg |  | 4 |  | 3.8 | 0.006 |  |  |  |  |  |  |  |  |  |  |  |  |  |  |  |  |  |  |
| Bottom | Signal | 0.5 oz+plating | 2.1 |  |  |  | S12 | 6.75(L11) | 50.17 |  |  | S12 | 6.5(L11) | 5 | 84.97 |  |  |  | 5(L11) | 6.5 | 99.87 |  |  |  |
|  | Mask |  | 0.5 |  | 3.4 | 0.025 |  |  |  |  |  |  |  |  |  |  |  |  |  |  |  |  |  |  |
| Thickness requirement: 2.36 ± 10% mm |  | mil | 92.79999999999998 |  |  |  |  |  |  |  |  |  |  |  |  |  |  |  |  |  |  |  |  |  |
|  |  | mm | 2.3571247142494283 |  |  |  |  |  |  |  |  |  |  |  |  |  |  |  |  |  |  |  |  |  |
| Note: | 1. Unit is mil |  |  |  |  |  |  |  |  |  |  |  |  |  |  |  |  |  |  |  |  |  |  |  |
|  | 2. The total thickness includes trace and solder mask. |  |  |  |  |  |  |  |  |  |  |  |  |  |  |  |  |  |  |  |  |  |  |  |
|  | 3. Minimum hole copper thickness is 1.0 mil. |  |  |  |  |  |  |  |  |  |  |  |  |  |  |  |  |  |  |  |  |  |  |  |
|  | 4. Minimum surface copper thickness 1.5 mil. |  |  |  |  |  |  |  |  |  |  |  |  |  |  |  |  |  |  |  |  |  |  |  |
|  | 5. If there is no controlled impedance line described as the stackup in the gerber file, PCB supplier can ignore this kind of impedance control directly, but need to inform Wiwynn in engineering question(EQ). |  |  |  |  |  |  |  |  |  |  |  |  |  |  |  |  |  |  |  |  |  |  |  |
|  | 6. PCB test coupon requirement and PCB test note are described in the another sheets. |  |  |  |  |  |  |  |  |  |  |  |  |  |  |  |  |  |  |  |  |  |  |  |
|  | 7. If there is no "Delta-L" design in gerber file, PCB supplier should design 85 ohm "Delta-L" angle routing coupon and provide the measurement results in FAI report which meet the following criteria: |  |  |  |  |  |  |  |  |  |  |  |  |  |  |  |  |  |  |  |  |  |  |  |
|  | For low-loss material |  |  |  |  |  |  |  |  |  |  |  |  |  |  |  |  |  |  |  |  |  |  |  |
|  | (1)   0.55 dB/inch @ 4GHz; 1.05 dB/inch @ 8GHz for microstrip routing |  |  |  |  |  |  |  |  |  |  |  |  |  |  |  |  |  |  |  |  |  |  |  |
|  | (2)   0.48 dB/inch @ 4GHz; 0.9 dB/inch @ 8GHz for stripline routing |  |  |  |  |  |  |  |  |  |  |  |  |  |  |  |  |  |  |  |  |  |  |  |
